(kicad_pcb
	(version 20260206)
	(generator "pcbnew")
	(generator_version "10.0")
	(general
		(thickness 1.6)
		(legacy_teardrops no)
	)
	(paper "A4")
	(title_block
		(title "v1-chassis-manager — T6M_CM_d_v01_1031_1645.brd")
		(comment 1 "Open CloudServer (Microsoft) / footprints 206-214 of 2512")
	)
	(layers
		(0 "F.Cu" signal "TOP")
		(4 "In1.Cu" signal "GND1")
		(6 "In2.Cu" signal "IN1")
		(8 "In3.Cu" signal "VCC1")
		(10 "In4.Cu" signal "VCC2")
		(12 "In5.Cu" signal "GND2")
		(14 "In6.Cu" signal "IN2")
		(16 "In7.Cu" signal "IN3")
		(18 "In8.Cu" signal "GND3")
		(2 "B.Cu" signal "BOTTOM")
		(9 "F.Adhes" user "F.Adhesive")
		(11 "B.Adhes" user "B.Adhesive")
		(13 "F.Paste" user "Package Geometry/Pastemask Top")
		(15 "B.Paste" user "Package Geometry/Pastemask Bottom")
		(5 "F.SilkS" user "Ref Des/Silkscreen Top")
		(7 "B.SilkS" user "Ref Des/Silkscreen Bottom")
		(1 "F.Mask" user "Board Geometry/Soldermask Top")
		(3 "B.Mask" user "Board Geometry/Soldermask Bottom")
		(17 "Dwgs.User" user "User.Drawings")
		(19 "Cmts.User" user "User.Comments")
		(21 "Eco1.User" user "User.Eco1")
		(23 "Eco2.User" user "User.Eco2")
		(25 "Edge.Cuts" user "Board Geometry/Outline")
		(27 "Margin" user)
		(31 "F.CrtYd" user "Package Geometry/Place Bound Top")
		(29 "B.CrtYd" user "Package Geometry/Place Bound Bottom")
		(35 "F.Fab" user "Ref Des/Assembly Top")
		(33 "B.Fab" user "Ref Des/Assembly Bottom")
	)
	(footprint ""
		(layer "F.Cu")
		(at 52.17414 -163.89985 90)
		(property "Reference" "R539"
			(at -131.03606 -3.360928 90)
			(unlocked yes)
			(layer "F.SilkS")
			(effects
				(font
					(size 0.7874 0.5842)
					(thickness 0.1524)
				)
				(justify left)
			)
		)
		(property "Value" ""
			(at 0 0 90)
			(layer "F.Fab")
			(effects
				(font
					(size 1.27 1.27)
				)
			)
		)
		(duplicate_pad_numbers_are_jumpers no)
		(fp_line
			(start 0.7874 -0.4064)
			(end 0.7874 0.4064)
			(stroke
				(width 0.1524)
				(type default)
			)
			(layer "F.SilkS")
		)
		(fp_line
			(start -0.7874 -0.4064)
			(end 0.7874 -0.4064)
			(stroke
				(width 0.1524)
				(type default)
			)
			(layer "F.SilkS")
		)
		(fp_line
			(start 0.7874 0.4064)
			(end -0.7874 0.4064)
			(stroke
				(width 0.1524)
				(type default)
			)
			(layer "F.SilkS")
		)
		(fp_line
			(start -0.7874 0.4064)
			(end -0.7874 -0.4064)
			(stroke
				(width 0.1524)
				(type default)
			)
			(layer "F.SilkS")
		)
		(fp_poly
			(pts
				(xy -0.508 0.2794) (xy -0.508 0.2286) (xy -0.635 0.2286) (xy -0.635 -0.254) (xy -0.5334 -0.254)
				(xy -0.5334 -0.2794) (xy 0.5334 -0.2794) (xy 0.5334 -0.254) (xy 0.635 -0.254) (xy 0.635 0.254) (xy 0.5334 0.254)
				(xy 0.5334 0.2794)
			)
			(stroke
				(width 0)
				(type default)
			)
			(fill no)
			(layer "F.CrtYd")
		)
		(pad "1" smd rect
			(at 0.40005 0 90)
			(size 0.4572 0.508)
			(layers "F.Cu" "F.Mask" "F.Paste")
			(net "P3V3_NODE1")
		)
		(pad "2" smd rect
			(at -0.40005 0 90)
			(size 0.4572 0.508)
			(layers "F.Cu" "F.Mask" "F.Paste")
			(net "SMB_LAN1_CLK")
		)
	)
	(footprint ""
		(layer "F.Cu")
		(at 155.926028 -176.083722 90)
		(property "Reference" "R1304"
			(at -0.647192 1.858772 90)
			(unlocked yes)
			(layer "F.SilkS")
			(effects
				(font
					(size 0.7874 0.5842)
					(thickness 0.1524)
				)
				(justify left)
			)
		)
		(property "Value" ""
			(at 0 0 90)
			(layer "F.Fab")
			(effects
				(font
					(size 1.27 1.27)
				)
			)
		)
		(duplicate_pad_numbers_are_jumpers no)
		(fp_line
			(start 0.7874 -0.4064)
			(end 0.7874 0.4064)
			(stroke
				(width 0.1524)
				(type default)
			)
			(layer "F.SilkS")
		)
		(fp_line
			(start -0.7874 -0.4064)
			(end 0.7874 -0.4064)
			(stroke
				(width 0.1524)
				(type default)
			)
			(layer "F.SilkS")
		)
		(fp_line
			(start 0.7874 0.4064)
			(end -0.7874 0.4064)
			(stroke
				(width 0.1524)
				(type default)
			)
			(layer "F.SilkS")
		)
		(fp_line
			(start -0.7874 0.4064)
			(end -0.7874 -0.4064)
			(stroke
				(width 0.1524)
				(type default)
			)
			(layer "F.SilkS")
		)
		(fp_poly
			(pts
				(xy -0.508 0.2794) (xy -0.508 0.2286) (xy -0.635 0.2286) (xy -0.635 -0.254) (xy -0.5334 -0.254)
				(xy -0.5334 -0.2794) (xy 0.5334 -0.2794) (xy 0.5334 -0.254) (xy 0.635 -0.254) (xy 0.635 0.254) (xy 0.5334 0.254)
				(xy 0.5334 0.2794)
			)
			(stroke
				(width 0)
				(type default)
			)
			(fill no)
			(layer "F.CrtYd")
		)
		(pad "1" smd rect
			(at 0.40005 0 90)
			(size 0.4572 0.508)
			(layers "F.Cu" "F.Mask" "F.Paste")
			(net "P3V3_NODE1")
		)
		(pad "2" smd rect
			(at -0.40005 0 90)
			(size 0.4572 0.508)
			(layers "F.Cu" "F.Mask" "F.Paste")
			(net "N54365556")
		)
	)
	(footprint ""
		(layer "F.Cu")
		(at 94.451932 -173.290992)
		(property "Reference" "R764"
			(at 86.67369 74.174096 0)
			(unlocked yes)
			(layer "F.SilkS")
			(effects
				(font
					(size 0.7874 0.5842)
					(thickness 0.1524)
				)
				(justify left)
			)
		)
		(property "Value" ""
			(at 0 0 0)
			(layer "F.Fab")
			(effects
				(font
					(size 1.27 1.27)
				)
			)
		)
		(duplicate_pad_numbers_are_jumpers no)
		(fp_line
			(start -0.7874 -0.4064)
			(end 0.7874 -0.4064)
			(stroke
				(width 0.1524)
				(type default)
			)
			(layer "F.SilkS")
		)
		(fp_line
			(start -0.7874 0.4064)
			(end -0.7874 -0.4064)
			(stroke
				(width 0.1524)
				(type default)
			)
			(layer "F.SilkS")
		)
		(fp_line
			(start 0.7874 -0.4064)
			(end 0.7874 0.4064)
			(stroke
				(width 0.1524)
				(type default)
			)
			(layer "F.SilkS")
		)
		(fp_line
			(start 0.7874 0.4064)
			(end -0.7874 0.4064)
			(stroke
				(width 0.1524)
				(type default)
			)
			(layer "F.SilkS")
		)
		(fp_poly
			(pts
				(xy -0.508 0.2794) (xy -0.508 0.2286) (xy -0.635 0.2286) (xy -0.635 -0.254) (xy -0.5334 -0.254)
				(xy -0.5334 -0.2794) (xy 0.5334 -0.2794) (xy 0.5334 -0.254) (xy 0.635 -0.254) (xy 0.635 0.254) (xy 0.5334 0.254)
				(xy 0.5334 0.2794)
			)
			(stroke
				(width 0)
				(type default)
			)
			(fill no)
			(layer "F.CrtYd")
		)
		(pad "1" smd rect
			(at 0.40005 0)
			(size 0.4572 0.508)
			(layers "F.Cu" "F.Mask" "F.Paste")
			(net "I2C_SCL_FANCTRL1_R")
		)
		(pad "2" smd rect
			(at -0.40005 0)
			(size 0.4572 0.508)
			(layers "F.Cu" "F.Mask" "F.Paste")
			(net "I2C_COM3_SCL")
		)
	)
	(footprint ""
		(layer "F.Cu")
		(at 12.6365 -131.590288 180)
		(property "Reference" "PR30"
			(at 4.026662 -0.012446 0)
			(unlocked yes)
			(layer "F.SilkS")
			(effects
				(font
					(size 0.7874 0.5842)
					(thickness 0.1524)
				)
				(justify left)
			)
		)
		(property "Value" ""
			(at 0 0 180)
			(layer "F.Fab")
			(effects
				(font
					(size 1.27 1.27)
				)
			)
		)
		(duplicate_pad_numbers_are_jumpers no)
		(fp_line
			(start 0.7874 0.4064)
			(end -0.7874 0.4064)
			(stroke
				(width 0.1524)
				(type default)
			)
			(layer "F.SilkS")
		)
		(fp_line
			(start 0.7874 -0.4064)
			(end 0.7874 0.4064)
			(stroke
				(width 0.1524)
				(type default)
			)
			(layer "F.SilkS")
		)
		(fp_line
			(start -0.7874 0.4064)
			(end -0.7874 -0.4064)
			(stroke
				(width 0.1524)
				(type default)
			)
			(layer "F.SilkS")
		)
		(fp_line
			(start -0.7874 -0.4064)
			(end 0.7874 -0.4064)
			(stroke
				(width 0.1524)
				(type default)
			)
			(layer "F.SilkS")
		)
		(fp_poly
			(pts
				(xy -0.508 0.2794) (xy -0.508 0.2286) (xy -0.635 0.2286) (xy -0.635 -0.254) (xy -0.5334 -0.254)
				(xy -0.5334 -0.2794) (xy 0.5334 -0.2794) (xy 0.5334 -0.254) (xy 0.635 -0.254) (xy 0.635 0.254) (xy 0.5334 0.254)
				(xy 0.5334 0.2794)
			)
			(stroke
				(width 0)
				(type default)
			)
			(fill no)
			(layer "F.CrtYd")
		)
		(pad "1" smd rect
			(at 0.40005 0 180)
			(size 0.4572 0.508)
			(layers "F.Cu" "F.Mask" "F.Paste")
			(net "P1V05_NODE1")
		)
		(pad "2" smd rect
			(at -0.40005 0 180)
			(size 0.4572 0.508)
			(layers "F.Cu" "F.Mask" "F.Paste")
			(net "VSENSE_P1V05_NODE1_P")
		)
	)
	(footprint ""
		(layer "F.Cu")
		(at 69.242686 -169.87393)
		(property "Reference" "C885"
			(at -2.755646 1.095502 0)
			(unlocked yes)
			(layer "F.SilkS")
			(effects
				(font
					(size 0.7874 0.5842)
					(thickness 0.1524)
				)
			)
		)
		(property "Value" ""
			(at 0 0 0)
			(layer "F.Fab")
			(effects
				(font
					(size 1.27 1.27)
				)
			)
		)
		(duplicate_pad_numbers_are_jumpers no)
		(fp_line
			(start -1.2954 -0.5842)
			(end 1.2954 -0.5842)
			(stroke
				(width 0.1524)
				(type default)
			)
			(layer "F.SilkS")
		)
		(fp_line
			(start -1.2954 0.5842)
			(end -1.2954 -0.5842)
			(stroke
				(width 0.1524)
				(type default)
			)
			(layer "F.SilkS")
		)
		(fp_line
			(start 0 -0.5842)
			(end 0 0.5842)
			(stroke
				(width 0.1524)
				(type default)
			)
			(layer "F.SilkS")
		)
		(fp_line
			(start 1.2954 -0.5842)
			(end 1.2954 0.5842)
			(stroke
				(width 0.1524)
				(type default)
			)
			(layer "F.SilkS")
		)
		(fp_line
			(start 1.2954 0.5842)
			(end -1.2954 0.5842)
			(stroke
				(width 0.1524)
				(type default)
			)
			(layer "F.SilkS")
		)
		(fp_poly
			(pts
				(xy 0.8636 -0.4572) (xy 0.8636 -0.3556) (xy 1.143 -0.3556) (xy 1.143 0.3556) (xy 0.8636 0.3556)
				(xy 0.8636 0.4572) (xy -0.8636 0.4572) (xy -0.8636 0.3556) (xy -1.143 0.3556) (xy -1.143 -0.3556)
				(xy -0.8636 -0.3556) (xy -0.8636 -0.4572)
			)
			(stroke
				(width 0)
				(type default)
			)
			(fill no)
			(layer "F.CrtYd")
		)
		(fp_line
			(start -0.884936 -0.504952)
			(end 0.884936 -0.504952)
			(stroke
				(width 0.1)
				(type default)
			)
			(layer "F.Fab")
		)
		(fp_line
			(start -0.884936 0.504952)
			(end -0.884936 -0.504952)
			(stroke
				(width 0.1)
				(type default)
			)
			(layer "F.Fab")
		)
		(fp_line
			(start 0.884936 -0.504952)
			(end 0.884936 0.504952)
			(stroke
				(width 0.1)
				(type default)
			)
			(layer "F.Fab")
		)
		(fp_line
			(start 0.884936 0.504952)
			(end -0.884936 0.504952)
			(stroke
				(width 0.1)
				(type default)
			)
			(layer "F.Fab")
		)
		(pad "1" smd rect
			(at 0.7366 0 90)
			(size 0.7112 0.8128)
			(layers "F.Cu" "F.Mask" "F.Paste")
			(net "P3V3_NODE1")
		)
		(pad "2" smd rect
			(at -0.7366 0 90)
			(size 0.7112 0.8128)
			(layers "F.Cu" "F.Mask" "F.Paste")
			(net "GND")
		)
	)
	(footprint ""
		(layer "F.Cu")
		(at 86.744048 -128.998726 -90)
		(property "Reference" "R1255"
			(at 5.940044 4.769104 90)
			(unlocked yes)
			(layer "F.SilkS")
			(effects
				(font
					(size 0.7874 0.5842)
					(thickness 0.1524)
				)
				(justify left)
			)
		)
		(property "Value" ""
			(at 0 0 270)
			(layer "F.Fab")
			(effects
				(font
					(size 1.27 1.27)
				)
			)
		)
		(duplicate_pad_numbers_are_jumpers no)
		(fp_line
			(start -0.7874 0.4064)
			(end -0.7874 -0.4064)
			(stroke
				(width 0.1524)
				(type default)
			)
			(layer "F.SilkS")
		)
		(fp_line
			(start 0.7874 0.4064)
			(end -0.7874 0.4064)
			(stroke
				(width 0.1524)
				(type default)
			)
			(layer "F.SilkS")
		)
		(fp_line
			(start -0.7874 -0.4064)
			(end 0.7874 -0.4064)
			(stroke
				(width 0.1524)
				(type default)
			)
			(layer "F.SilkS")
		)
		(fp_line
			(start 0.7874 -0.4064)
			(end 0.7874 0.4064)
			(stroke
				(width 0.1524)
				(type default)
			)
			(layer "F.SilkS")
		)
		(fp_poly
			(pts
				(xy -0.508 0.2794) (xy -0.508 0.2286) (xy -0.635 0.2286) (xy -0.635 -0.254) (xy -0.5334 -0.254)
				(xy -0.5334 -0.2794) (xy 0.5334 -0.2794) (xy 0.5334 -0.254) (xy 0.635 -0.254) (xy 0.635 0.254) (xy 0.5334 0.254)
				(xy 0.5334 0.2794)
			)
			(stroke
				(width 0)
				(type default)
			)
			(fill no)
			(layer "F.CrtYd")
		)
		(pad "1" smd rect
			(at 0.40005 0 270)
			(size 0.4572 0.508)
			(layers "F.Cu" "F.Mask" "F.Paste")
			(net "PORT80_LOUT3")
		)
		(pad "2" smd rect
			(at -0.40005 0 270)
			(size 0.4572 0.508)
			(layers "F.Cu" "F.Mask" "F.Paste")
			(net "N53313501")
		)
	)
	(footprint ""
		(layer "F.Cu")
		(at 6.862572 -3.711194 -90)
		(property "Reference" "C179"
			(at 1.545844 2.645664 90)
			(unlocked yes)
			(layer "F.SilkS")
			(effects
				(font
					(size 0.7874 0.5842)
					(thickness 0.1524)
				)
				(justify left)
			)
		)
		(property "Value" ""
			(at 0 0 270)
			(layer "F.Fab")
			(effects
				(font
					(size 1.27 1.27)
				)
			)
		)
		(duplicate_pad_numbers_are_jumpers no)
		(fp_line
			(start -0.7874 0.4064)
			(end -0.7874 -0.4064)
			(stroke
				(width 0.1524)
				(type default)
			)
			(layer "F.SilkS")
		)
		(fp_line
			(start 0.7874 0.4064)
			(end -0.7874 0.4064)
			(stroke
				(width 0.1524)
				(type default)
			)
			(layer "F.SilkS")
		)
		(fp_line
			(start 0 0.381)
			(end 0 -0.381)
			(stroke
				(width 0.1524)
				(type default)
			)
			(layer "F.SilkS")
		)
		(fp_line
			(start -0.7874 -0.4064)
			(end 0.7874 -0.4064)
			(stroke
				(width 0.1524)
				(type default)
			)
			(layer "F.SilkS")
		)
		(fp_line
			(start 0.7874 -0.4064)
			(end 0.7874 0.4064)
			(stroke
				(width 0.1524)
				(type default)
			)
			(layer "F.SilkS")
		)
		(fp_poly
			(pts
				(xy -0.5334 0.254) (xy -0.635 0.254) (xy -0.635 0.2286) (xy -0.635 -0.254) (xy -0.5334 -0.254) (xy -0.5334 -0.2794)
				(xy 0.5334 -0.2794) (xy 0.5334 -0.254) (xy 0.635 -0.254) (xy 0.635 0.254) (xy 0.5334 0.254) (xy 0.5334 0.2794)
				(xy -0.508 0.2794) (xy -0.5334 0.2794)
			)
			(stroke
				(width 0)
				(type default)
			)
			(fill no)
			(layer "F.CrtYd")
		)
		(pad "1" smd rect
			(at 0.40005 0 270)
			(size 0.4572 0.508)
			(layers "F.Cu" "F.Mask" "F.Paste")
			(net "P3V3_STB_NODE1")
		)
		(pad "2" smd rect
			(at -0.40005 0 270)
			(size 0.4572 0.508)
			(layers "F.Cu" "F.Mask" "F.Paste")
			(net "GND")
		)
	)
	(footprint ""
		(layer "F.Cu")
		(at 103.828342 -151.711152 180)
		(property "Reference" "PC35"
			(at 1.052576 -3.409696 90)
			(unlocked yes)
			(layer "F.SilkS")
			(effects
				(font
					(size 0.7874 0.5842)
					(thickness 0.1524)
				)
				(justify left)
			)
		)
		(property "Value" ""
			(at 0 0 180)
			(layer "F.Fab")
			(effects
				(font
					(size 1.27 1.27)
				)
			)
		)
		(duplicate_pad_numbers_are_jumpers no)
		(fp_line
			(start 0.7874 0.4064)
			(end -0.7874 0.4064)
			(stroke
				(width 0.1524)
				(type default)
			)
			(layer "F.SilkS")
		)
		(fp_line
			(start 0.7874 -0.4064)
			(end 0.7874 0.4064)
			(stroke
				(width 0.1524)
				(type default)
			)
			(layer "F.SilkS")
		)
		(fp_line
			(start 0 0.381)
			(end 0 -0.381)
			(stroke
				(width 0.1524)
				(type default)
			)
			(layer "F.SilkS")
		)
		(fp_line
			(start -0.7874 0.4064)
			(end -0.7874 -0.4064)
			(stroke
				(width 0.1524)
				(type default)
			)
			(layer "F.SilkS")
		)
		(fp_line
			(start -0.7874 -0.4064)
			(end 0.7874 -0.4064)
			(stroke
				(width 0.1524)
				(type default)
			)
			(layer "F.SilkS")
		)
		(fp_poly
			(pts
				(xy -0.5334 0.254) (xy -0.635 0.254) (xy -0.635 0.2286) (xy -0.635 -0.254) (xy -0.5334 -0.254) (xy -0.5334 -0.2794)
				(xy 0.5334 -0.2794) (xy 0.5334 -0.254) (xy 0.635 -0.254) (xy 0.635 0.254) (xy 0.5334 0.254) (xy 0.5334 0.2794)
				(xy -0.508 0.2794) (xy -0.5334 0.2794)
			)
			(stroke
				(width 0)
				(type default)
			)
			(fill no)
			(layer "F.CrtYd")
		)
		(pad "1" smd rect
			(at 0.40005 0 180)
			(size 0.4572 0.508)
			(layers "F.Cu" "F.Mask" "F.Paste")
			(net "P5V_STB_NODE1")
		)
		(pad "2" smd rect
			(at -0.40005 0 180)
			(size 0.4572 0.508)
			(layers "F.Cu" "F.Mask" "F.Paste")
			(net "GND")
		)
	)
	(footprint ""
		(layer "F.Cu")
		(at 66.194686 -121.044462 -90)
		(property "Reference" "R346"
			(at 6.142736 -7.938516 90)
			(unlocked yes)
			(layer "F.SilkS")
			(effects
				(font
					(size 0.7874 0.5842)
					(thickness 0.1524)
				)
				(justify left)
			)
		)
		(property "Value" ""
			(at 0 0 270)
			(layer "F.Fab")
			(effects
				(font
					(size 1.27 1.27)
				)
			)
		)
		(duplicate_pad_numbers_are_jumpers no)
		(fp_line
			(start -0.7874 0.4064)
			(end -0.7874 -0.4064)
			(stroke
				(width 0.1524)
				(type default)
			)
			(layer "F.SilkS")
		)
		(fp_line
			(start 0.7874 0.4064)
			(end -0.7874 0.4064)
			(stroke
				(width 0.1524)
				(type default)
			)
			(layer "F.SilkS")
		)
		(fp_line
			(start -0.7874 -0.4064)
			(end 0.7874 -0.4064)
			(stroke
				(width 0.1524)
				(type default)
			)
			(layer "F.SilkS")
		)
		(fp_line
			(start 0.7874 -0.4064)
			(end 0.7874 0.4064)
			(stroke
				(width 0.1524)
				(type default)
			)
			(layer "F.SilkS")
		)
		(fp_poly
			(pts
				(xy -0.508 0.2794) (xy -0.508 0.2286) (xy -0.635 0.2286) (xy -0.635 -0.254) (xy -0.5334 -0.254)
				(xy -0.5334 -0.2794) (xy 0.5334 -0.2794) (xy 0.5334 -0.254) (xy 0.635 -0.254) (xy 0.635 0.254) (xy 0.5334 0.254)
				(xy 0.5334 0.2794)
			)
			(stroke
				(width 0)
				(type default)
			)
			(fill no)
			(layer "F.CrtYd")
		)
		(pad "1" smd rect
			(at 0.40005 0 270)
			(size 0.4572 0.508)
			(layers "F.Cu" "F.Mask" "F.Paste")
			(net "P3V3_NODE1")
		)
		(pad "2" smd rect
			(at -0.40005 0 270)
			(size 0.4572 0.508)
			(layers "F.Cu" "F.Mask" "F.Paste")
			(net "PU_I2C_BMC_SCL")
		)
	)
)
